(kicad_pcb
	(version 20260206)
	(generator "pcbnew")
	(generator_version "10.0")
	(general
		(thickness 1.6)
		(legacy_teardrops no)
	)
	(paper "A4")
	(title_block
		(title "Wiwynn_Tioga_Pass_MB.brd")
		(comment 1 "Tioga Pass / footprints 1118-1122 of 4770")
	)
	(layers
		(0 "F.Cu" signal "TOP")
		(4 "In1.Cu" signal "L2GND")
		(6 "In2.Cu" signal "L3")
		(8 "In3.Cu" signal "L4GND")
		(10 "In4.Cu" signal "L5")
		(12 "In5.Cu" signal "L6GND")
		(14 "In6.Cu" signal "L7VCC")
		(16 "In7.Cu" signal "L8VCC")
		(18 "In8.Cu" signal "L9GND")
		(20 "In9.Cu" signal "L10")
		(22 "In10.Cu" signal "L11GND")
		(24 "In11.Cu" signal "L12")
		(26 "In12.Cu" signal "L13GND")
		(2 "B.Cu" signal "BOTTOM")
		(9 "F.Adhes" user "F.Adhesive")
		(11 "B.Adhes" user "B.Adhesive")
		(13 "F.Paste" user "Package Geometry/Pastemask Top")
		(15 "B.Paste" user "Package Geometry/Pastemask Bottom")
		(5 "F.SilkS" user "Ref Des/Silkscreen Top")
		(7 "B.SilkS" user "Ref Des/Silkscreen Bottom")
		(1 "F.Mask" user "Board Geometry/Soldermask Top")
		(3 "B.Mask" user "Board Geometry/Soldermask Bottom")
		(17 "Dwgs.User" user "User.Drawings")
		(19 "Cmts.User" user "User.Comments")
		(21 "Eco1.User" user "User.Eco1")
		(23 "Eco2.User" user "User.Eco2")
		(25 "Edge.Cuts" user "Board Geometry/Outline")
		(27 "Margin" user)
		(31 "F.CrtYd" user "Package Geometry/Place Bound Top")
		(29 "B.CrtYd" user "Package Geometry/Place Bound Bottom")
		(35 "F.Fab" user "Ref Des/Assembly Top")
		(33 "B.Fab" user "Ref Des/Assembly Bottom")
	)
	(footprint ""
		(layer "F.Cu")
		(at 487.970576 -28.408376 180)
		(property "Reference" "R9F63"
			(at 0 0 180)
			(layer "F.SilkS")
			(hide yes)
			(effects
				(font
					(size 1.27 1.27)
				)
			)
		)
		(property "Value" ""
			(at 0 0 180)
			(layer "F.Fab")
			(effects
				(font
					(size 1.27 1.27)
				)
			)
		)
		(duplicate_pad_numbers_are_jumpers no)
		(fp_poly
			(pts
				(xy -0.2794 -0.1016) (xy 0.2794 -0.1016) (xy 0.2794 0.9906) (xy -0.2794 0.9906)
			)
			(stroke
				(width 0)
				(type default)
			)
			(fill no)
			(layer "F.CrtYd")
		)
		(fp_line
			(start 0.2794 0.9906)
			(end 0.2794 -0.1016)
			(stroke
				(width 0.1)
				(type default)
			)
			(layer "F.Fab")
		)
		(fp_line
			(start 0.2794 -0.1016)
			(end -0.2794 -0.1016)
			(stroke
				(width 0.1)
				(type default)
			)
			(layer "F.Fab")
		)
		(fp_line
			(start -0.2794 0.9906)
			(end 0.2794 0.9906)
			(stroke
				(width 0.1)
				(type default)
			)
			(layer "F.Fab")
		)
		(fp_line
			(start -0.2794 -0.1016)
			(end -0.2794 0.9906)
			(stroke
				(width 0.1)
				(type default)
			)
			(layer "F.Fab")
		)
		(pad "1" smd rect
			(at 0 0 180)
			(size 0.508 0.508)
			(layers "F.Cu" "F.Mask" "F.Paste")
			(net "SPA_MID_DBG_RX")
		)
		(pad "2" smd rect
			(at 0 0.889 180)
			(size 0.508 0.508)
			(layers "F.Cu" "F.Mask" "F.Paste")
			(net "SPA_MID_DBG_RX_R")
		)
		(zone
			(layer "F.Cu")
			(hatch none 0.5)
			(connect_pads
				(clearance 0)
			)
			(min_thickness 0.25)
			(keepout
				(tracks not_allowed)
				(vias allowed)
				(pads allowed)
				(copperpour not_allowed)
				(footprints allowed)
			)
			(placement
				(enabled no)
				(sheetname "")
			)
			(fill
				(thermal_gap 0.5)
				(thermal_bridge_width 0.5)
				(island_removal_mode 0)
			)
			(polygon
				(pts
					(xy 488.224576 -29.043376) (xy 487.716576 -29.043376) (xy 487.716576 -28.662376) (xy 488.224576 -28.662376)
				)
			)
		)
		(zone
			(layer "F.Cu")
			(hatch none 0.5)
			(connect_pads
				(clearance 0)
			)
			(min_thickness 0.25)
			(keepout
				(tracks allowed)
				(vias not_allowed)
				(pads allowed)
				(copperpour not_allowed)
				(footprints allowed)
			)
			(placement
				(enabled no)
				(sheetname "")
			)
			(fill
				(thermal_gap 0.5)
				(thermal_bridge_width 0.5)
				(island_removal_mode 0)
			)
			(polygon
				(pts
					(xy 488.224576 -28.662376) (xy 487.716576 -28.662376) (xy 487.716576 -29.043376) (xy 488.224576 -29.043376)
				)
			)
		)
	)
	(footprint ""
		(layer "F.Cu")
		(at 24.123142 -86.380066 180)
		(property "Reference" "CF7"
			(at 0 0 180)
			(layer "F.SilkS")
			(hide yes)
			(effects
				(font
					(size 1.27 1.27)
				)
			)
		)
		(property "Value" "*"
			(at 1.1811 -2.8194 180)
			(unlocked yes)
			(layer "F.Fab")
			(hide yes)
			(effects
				(font
					(size 1.27 1.016)
					(thickness 0.1524)
				)
			)
		)
		(property "Device Type" "SC22P50V2JN-4GP_SMD-BCG-SC22P5A"
			(at 1.1811 -4.3434 180)
			(unlocked yes)
			(layer "F.Fab")
			(hide yes)
			(effects
				(font
					(size 1.27 1.016)
					(thickness 0.1524)
				)
			)
		)
		(duplicate_pad_numbers_are_jumpers no)
		(fp_rect
			(start -0.4318 0.9525)
			(end 0.4318 -0.9525)
			(stroke
				(width 0)
				(type default)
			)
			(fill no)
			(layer "F.CrtYd")
		)
		(fp_rect
			(start -0.4318 0.9525)
			(end 0.4318 -0.9525)
			(stroke
				(width 0)
				(type default)
			)
			(fill no)
			(layer "F.Fab")
		)
		(pad "1" smd custom
			(at 0 -0.4445 180)
			(size 0.1524 0.1524)
			(layers "F.Cu" "F.Mask" "F.Paste")
			(net "VR_PVCCIN_CPU1_AIREF1")
			(options
				(clearance outline)
				(anchor circle)
			)
			(primitives
				(gr_poly
					(pts
						(arc
							(start 0.3048 -0.2032)
							(mid 0.275042 -0.275042)
							(end 0.2032 -0.3048)
						)
						(arc
							(start -0.2032 -0.3048)
							(mid -0.275042 -0.275042)
							(end -0.3048 -0.2032)
						)
						(arc
							(start -0.3048 0.2032)
							(mid -0.275042 0.275042)
							(end -0.2032 0.3048)
						)
						(arc
							(start 0.2032 0.3048)
							(mid 0.275042 0.275042)
							(end 0.3048 0.2032)
						)
					)
					(width 0)
					(fill yes)
				)
			)
		)
		(pad "2" smd custom
			(at 0 0.4445 180)
			(size 0.1524 0.1524)
			(layers "F.Cu" "F.Mask" "F.Paste")
			(net "ISENSE_PVCCIN_CPU1_PH1_IMON")
			(options
				(clearance outline)
				(anchor circle)
			)
			(primitives
				(gr_poly
					(pts
						(arc
							(start 0.3048 -0.2032)
							(mid 0.275042 -0.275042)
							(end 0.2032 -0.3048)
						)
						(arc
							(start -0.2032 -0.3048)
							(mid -0.275042 -0.275042)
							(end -0.3048 -0.2032)
						)
						(arc
							(start -0.3048 0.2032)
							(mid -0.275042 0.275042)
							(end -0.2032 0.3048)
						)
						(arc
							(start 0.2032 0.3048)
							(mid 0.275042 0.275042)
							(end 0.3048 0.2032)
						)
					)
					(width 0)
					(fill yes)
				)
			)
		)
	)
	(footprint ""
		(layer "F.Cu")
		(at 403.733 0.1524)
		(property "Reference" "U1L10"
			(at -1.743964 -3.834638 0)
			(unlocked yes)
			(layer "F.SilkS")
			(effects
				(font
					(size 3.048 1.524)
					(thickness 0.000001)
				)
				(justify left)
			)
		)
		(property "Value" ""
			(at 0 0 0)
			(layer "F.Fab")
			(effects
				(font
					(size 1.27 1.27)
				)
			)
		)
		(duplicate_pad_numbers_are_jumpers no)
		(fp_circle
			(center -1.17856 -2.466086)
			(end -1.05156 -2.466086)
			(stroke
				(width 0.254)
				(type default)
			)
			(fill no)
			(layer "F.SilkS")
		)
		(fp_rect
			(start -0.9144 0.9144)
			(end 0.9144 -0.9144)
			(stroke
				(width 0)
				(type default)
			)
			(fill yes)
			(layer "F.Paste")
		)
		(fp_rect
			(start -1.82499 1.82499)
			(end 1.82499 -1.82499)
			(stroke
				(width 0)
				(type default)
			)
			(fill no)
			(layer "F.CrtYd")
		)
		(fp_line
			(start -1.82499 -1.82499)
			(end 1.82499 -1.82499)
			(stroke
				(width 0.1)
				(type default)
			)
			(layer "F.Fab")
		)
		(fp_line
			(start -1.82499 1.82499)
			(end -1.82499 -1.82499)
			(stroke
				(width 0.1)
				(type default)
			)
			(layer "F.Fab")
		)
		(fp_line
			(start 1.82499 -1.82499)
			(end 1.82499 1.82499)
			(stroke
				(width 0.1)
				(type default)
			)
			(layer "F.Fab")
		)
		(fp_line
			(start 1.82499 1.82499)
			(end -1.82499 1.82499)
			(stroke
				(width 0.1)
				(type default)
			)
			(layer "F.Fab")
		)
		(fp_circle
			(center -1.17856 -2.466086)
			(end -1.05156 -2.466086)
			(stroke
				(width 0.254)
				(type default)
			)
			(fill no)
			(layer "F.Fab")
		)
		(pad "1" smd custom
			(at -0.750062 -1.549908)
			(size 0.0762 0.0762)
			(layers "F.Cu" "F.Mask" "F.Paste")
			(net "BMC_JTAG_SEL_N_MUX")
			(options
				(clearance outline)
				(anchor circle)
			)
			(primitives
				(gr_poly
					(pts
						(xy 0.1524 -0.381)
						(arc
							(start 0.1524 0.2286)
							(mid 0 0.381)
							(end -0.1524 0.2286)
						)
						(xy -0.1524 -0.381)
					)
					(width 0)
					(fill yes)
				)
			)
		)
		(pad "2" smd custom
			(at -1.549908 -0.999998)
			(size 0.0762 0.0762)
			(layers "F.Cu" "F.Mask" "F.Paste")
			(net "JTAG_PLD_TDO_MUX")
			(options
				(clearance outline)
				(anchor circle)
			)
			(primitives
				(gr_poly
					(pts
						(xy -0.381 -0.1524)
						(arc
							(start 0.2286 -0.1524)
							(mid 0.381 0)
							(end 0.2286 0.1524)
						)
						(xy -0.381 0.1524)
					)
					(width 0)
					(fill yes)
				)
			)
		)
		(pad "3" smd custom
			(at -1.549908 -0.500126)
			(size 0.0762 0.0762)
			(layers "F.Cu" "F.Mask" "F.Paste")
			(net "JTAG_TDO")
			(options
				(clearance outline)
				(anchor circle)
			)
			(primitives
				(gr_poly
					(pts
						(xy -0.381 -0.1524)
						(arc
							(start 0.2286 -0.1524)
							(mid 0.381 0)
							(end 0.2286 0.1524)
						)
						(xy -0.381 0.1524)
					)
					(width 0)
					(fill yes)
				)
			)
		)
		(pad "4" smd custom
			(at -1.549908 0)
			(size 0.0762 0.0762)
			(layers "F.Cu" "F.Mask" "F.Paste")
			(net "BMC_JTAG_SEL_N_MUX")
			(options
				(clearance outline)
				(anchor circle)
			)
			(primitives
				(gr_poly
					(pts
						(xy -0.381 -0.1524)
						(arc
							(start 0.2286 -0.1524)
							(mid 0.381 0)
							(end 0.2286 0.1524)
						)
						(xy -0.381 0.1524)
					)
					(width 0)
					(fill yes)
				)
			)
		)
		(pad "5" smd custom
			(at -1.549908 0.500126)
			(size 0.0762 0.0762)
			(layers "F.Cu" "F.Mask" "F.Paste")
			(net "JTAG_PLD_TCK_MUX")
			(options
				(clearance outline)
				(anchor circle)
			)
			(primitives
				(gr_poly
					(pts
						(xy -0.381 -0.1524)
						(arc
							(start 0.2286 -0.1524)
							(mid 0.381 0)
							(end 0.2286 0.1524)
						)
						(xy -0.381 0.1524)
					)
					(width 0)
					(fill yes)
				)
			)
		)
		(pad "6" smd custom
			(at -1.549908 0.999998)
			(size 0.0762 0.0762)
			(layers "F.Cu" "F.Mask" "F.Paste")
			(net "JTAG_TCK")
			(options
				(clearance outline)
				(anchor circle)
			)
			(primitives
				(gr_poly
					(pts
						(xy -0.381 -0.1524)
						(arc
							(start 0.2286 -0.1524)
							(mid 0.381 0)
							(end 0.2286 0.1524)
						)
						(xy -0.381 0.1524)
					)
					(width 0)
					(fill yes)
				)
			)
		)
		(pad "7" smd custom
			(at -0.750062 1.549908)
			(size 0.0762 0.0762)
			(layers "F.Cu" "F.Mask" "F.Paste")
			(net "GND")
			(options
				(clearance outline)
				(anchor circle)
			)
			(primitives
				(gr_poly
					(pts
						(xy -0.1524 0.381)
						(arc
							(start -0.1524 -0.2286)
							(mid 0 -0.381)
							(end 0.1524 -0.2286)
						)
						(xy 0.1524 0.381)
					)
					(width 0)
					(fill yes)
				)
			)
		)
		(pad "8" smd custom
			(at 0.769874 1.549908)
			(size 0.0762 0.0762)
			(layers "F.Cu" "F.Mask" "F.Paste")
			(net "JTAG_TMS")
			(options
				(clearance outline)
				(anchor circle)
			)
			(primitives
				(gr_poly
					(pts
						(xy -0.1524 0.381)
						(arc
							(start -0.1524 -0.2286)
							(mid 0 -0.381)
							(end 0.1524 -0.2286)
						)
						(xy 0.1524 0.381)
					)
					(width 0)
					(fill yes)
				)
			)
		)
		(pad "9" smd custom
			(at 1.549908 0.999998)
			(size 0.0762 0.0762)
			(layers "F.Cu" "F.Mask" "F.Paste")
			(net "JTAG_PLD_TMS_MUX")
			(options
				(clearance outline)
				(anchor circle)
			)
			(primitives
				(gr_poly
					(pts
						(xy 0.381 0.1524)
						(arc
							(start -0.2286 0.1524)
							(mid -0.381 0)
							(end -0.2286 -0.1524)
						)
						(xy 0.381 -0.1524)
					)
					(width 0)
					(fill yes)
				)
			)
		)
		(pad "10" smd custom
			(at 1.549908 0.500126)
			(size 0.0762 0.0762)
			(layers "F.Cu" "F.Mask" "F.Paste")
			(net "BMC_JTAG_SEL_N_MUX")
			(options
				(clearance outline)
				(anchor circle)
			)
			(primitives
				(gr_poly
					(pts
						(xy 0.381 0.1524)
						(arc
							(start -0.2286 0.1524)
							(mid -0.381 0)
							(end -0.2286 -0.1524)
						)
						(xy 0.381 -0.1524)
					)
					(width 0)
					(fill yes)
				)
			)
		)
		(pad "11" smd custom
			(at 1.549908 0)
			(size 0.0762 0.0762)
			(layers "F.Cu" "F.Mask" "F.Paste")
			(net "JTAG_TDI")
			(options
				(clearance outline)
				(anchor circle)
			)
			(primitives
				(gr_poly
					(pts
						(xy 0.381 0.1524)
						(arc
							(start -0.2286 0.1524)
							(mid -0.381 0)
							(end -0.2286 -0.1524)
						)
						(xy 0.381 -0.1524)
					)
					(width 0)
					(fill yes)
				)
			)
		)
		(pad "12" smd custom
			(at 1.549908 -0.500126)
			(size 0.0762 0.0762)
			(layers "F.Cu" "F.Mask" "F.Paste")
			(net "JTAG_PLD_TDI_MUX")
			(options
				(clearance outline)
				(anchor circle)
			)
			(primitives
				(gr_poly
					(pts
						(xy 0.381 0.1524)
						(arc
							(start -0.2286 0.1524)
							(mid -0.381 0)
							(end -0.2286 -0.1524)
						)
						(xy 0.381 -0.1524)
					)
					(width 0)
					(fill yes)
				)
			)
		)
		(pad "13" smd custom
			(at 1.549908 -0.999998)
			(size 0.0762 0.0762)
			(layers "F.Cu" "F.Mask" "F.Paste")
			(net "BMC_JTAG_SEL_N_MUX")
			(options
				(clearance outline)
				(anchor circle)
			)
			(primitives
				(gr_poly
					(pts
						(xy 0.381 0.1524)
						(arc
							(start -0.2286 0.1524)
							(mid -0.381 0)
							(end -0.2286 -0.1524)
						)
						(xy 0.381 -0.1524)
					)
					(width 0)
					(fill yes)
				)
			)
		)
		(pad "14" smd custom
			(at 0.750062 -1.549908)
			(size 0.0762 0.0762)
			(layers "F.Cu" "F.Mask" "F.Paste")
			(net "P3V3_STBY")
			(options
				(clearance outline)
				(anchor circle)
			)
			(primitives
				(gr_poly
					(pts
						(xy 0.1524 -0.381)
						(arc
							(start 0.1524 0.2286)
							(mid 0 0.381)
							(end -0.1524 0.2286)
						)
						(xy -0.1524 -0.381)
					)
					(width 0)
					(fill yes)
				)
			)
		)
		(pad "15" smd rect
			(at 0 0)
			(size 1.8288 1.8288)
			(layers "F.Cu" "F.Mask" "F.Paste")
			(net "GND")
		)
	)
	(footprint ""
		(layer "F.Cu")
		(at 393.254992 -10.917936)
		(property "Reference" "C7G21"
			(at 0 0 0)
			(layer "F.SilkS")
			(hide yes)
			(effects
				(font
					(size 1.27 1.27)
				)
			)
		)
		(property "Value" ""
			(at 0 0 0)
			(layer "F.Fab")
			(effects
				(font
					(size 1.27 1.27)
				)
			)
		)
		(duplicate_pad_numbers_are_jumpers no)
		(fp_rect
			(start -0.3048 0.9906)
			(end 0.3048 -0.1016)
			(stroke
				(width 0)
				(type default)
			)
			(fill no)
			(layer "F.CrtYd")
		)
		(fp_line
			(start -0.3048 -0.1016)
			(end -0.3048 0.9906)
			(stroke
				(width 0.1)
				(type default)
			)
			(layer "F.Fab")
		)
		(fp_line
			(start -0.3048 0.9906)
			(end 0.3048 0.9906)
			(stroke
				(width 0.1)
				(type default)
			)
			(layer "F.Fab")
		)
		(fp_line
			(start 0.3048 -0.1016)
			(end -0.3048 -0.1016)
			(stroke
				(width 0.1)
				(type default)
			)
			(layer "F.Fab")
		)
		(fp_line
			(start 0.3048 0.9906)
			(end 0.3048 -0.1016)
			(stroke
				(width 0.1)
				(type default)
			)
			(layer "F.Fab")
		)
		(pad "1" smd rect
			(at 0 0)
			(size 0.508 0.508)
			(layers "F.Cu" "F.Mask" "F.Paste")
			(net "P3E_CPU0_PE2_SS_TXP<7>")
		)
		(pad "2" smd rect
			(at 0 0.889)
			(size 0.508 0.508)
			(layers "F.Cu" "F.Mask" "F.Paste")
			(net "P3E_CPU0_PE2_SS_C_TXP<7>")
		)
		(zone
			(layer "F.Cu")
			(hatch none 0.5)
			(connect_pads
				(clearance 0)
			)
			(min_thickness 0.25)
			(keepout
				(tracks not_allowed)
				(vias allowed)
				(pads allowed)
				(copperpour not_allowed)
				(footprints allowed)
			)
			(placement
				(enabled no)
				(sheetname "")
			)
			(fill
				(thermal_gap 0.5)
				(thermal_bridge_width 0.5)
				(island_removal_mode 0)
			)
			(polygon
				(pts
					(xy 393.000992 -10.282936) (xy 393.508992 -10.282936) (xy 393.508992 -10.663936) (xy 393.000992 -10.663936)
				)
			)
		)
		(zone
			(layer "F.Cu")
			(hatch none 0.5)
			(connect_pads
				(clearance 0)
			)
			(min_thickness 0.25)
			(keepout
				(tracks allowed)
				(vias not_allowed)
				(pads allowed)
				(copperpour not_allowed)
				(footprints allowed)
			)
			(placement
				(enabled no)
				(sheetname "")
			)
			(fill
				(thermal_gap 0.5)
				(thermal_bridge_width 0.5)
				(island_removal_mode 0)
			)
			(polygon
				(pts
					(xy 393.000992 -10.282936) (xy 393.508992 -10.282936) (xy 393.508992 -10.663936) (xy 393.000992 -10.663936)
				)
			)
		)
	)
	(footprint ""
		(layer "F.Cu")
		(at 437.9468 -128.6764 180)
		(property "Reference" "C8B7"
			(at 0 0 180)
			(layer "F.SilkS")
			(hide yes)
			(effects
				(font
					(size 1.27 1.27)
				)
			)
		)
		(property "Value" ""
			(at 0 0 180)
			(layer "F.Fab")
			(effects
				(font
					(size 1.27 1.27)
				)
			)
		)
		(duplicate_pad_numbers_are_jumpers no)
		(fp_poly
			(pts
				(xy 0.3048 -0.1016) (xy 0.3048 0.9906) (xy -0.3048 0.9906) (xy -0.3048 -0.1016)
			)
			(stroke
				(width 0)
				(type default)
			)
			(fill no)
			(layer "F.CrtYd")
		)
		(fp_line
			(start 0.3048 0.9906)
			(end 0.3048 -0.1016)
			(stroke
				(width 0.1)
				(type default)
			)
			(layer "F.Fab")
		)
		(fp_line
			(start 0.3048 -0.1016)
			(end -0.3048 -0.1016)
			(stroke
				(width 0.1)
				(type default)
			)
			(layer "F.Fab")
		)
		(fp_line
			(start -0.3048 0.9906)
			(end 0.3048 0.9906)
			(stroke
				(width 0.1)
				(type default)
			)
			(layer "F.Fab")
		)
		(fp_line
			(start -0.3048 -0.1016)
			(end -0.3048 0.9906)
			(stroke
				(width 0.1)
				(type default)
			)
			(layer "F.Fab")
		)
		(pad "1" smd rect
			(at 0 0 180)
			(size 0.508 0.508)
			(layers "F.Cu" "F.Mask" "F.Paste")
			(net "P5V")
		)
		(pad "2" smd rect
			(at 0 0.889 180)
			(size 0.508 0.508)
			(layers "F.Cu" "F.Mask" "F.Paste")
			(net "GND")
		)
		(zone
			(layer "F.Cu")
			(hatch none 0.5)
			(connect_pads
				(clearance 0)
			)
			(min_thickness 0.25)
			(keepout
				(tracks not_allowed)
				(vias allowed)
				(pads allowed)
				(copperpour not_allowed)
				(footprints allowed)
			)
			(placement
				(enabled no)
				(sheetname "")
			)
			(fill
				(thermal_gap 0.5)
				(thermal_bridge_width 0.5)
				(island_removal_mode 0)
			)
			(polygon
				(pts
					(xy 438.2008 -129.3114) (xy 437.6928 -129.3114) (xy 437.6928 -128.9304) (xy 438.2008 -128.9304)
				)
			)
		)
		(zone
			(layer "F.Cu")
			(hatch none 0.5)
			(connect_pads
				(clearance 0)
			)
			(min_thickness 0.25)
			(keepout
				(tracks allowed)
				(vias not_allowed)
				(pads allowed)
				(copperpour not_allowed)
				(footprints allowed)
			)
			(placement
				(enabled no)
				(sheetname "")
			)
			(fill
				(thermal_gap 0.5)
				(thermal_bridge_width 0.5)
				(island_removal_mode 0)
			)
			(polygon
				(pts
					(xy 438.2008 -128.9304) (xy 437.6928 -128.9304) (xy 437.6928 -129.3114) (xy 438.2008 -129.3114)
				)
			)
		)
	)
)
